(kicad_pcb
	(version 20260206)
	(generator "pcbnew")
	(generator_version "10.0")
	(general
		(thickness 1.6)
		(legacy_teardrops no)
	)
	(paper "A4")
	(title_block
		(title "fcb — Lightning_FCB_BRD.brd")
		(comment 1 "Lightning (Wiwynn / Facebook NVMe JBOF) / footprints 203-209 of 495")
	)
	(layers
		(0 "F.Cu" signal "TOP")
		(4 "In1.Cu" signal "L2GND")
		(6 "In2.Cu" signal "L3VCC")
		(2 "B.Cu" signal "BOTTOM")
		(9 "F.Adhes" user "F.Adhesive")
		(11 "B.Adhes" user "B.Adhesive")
		(13 "F.Paste" user "Package Geometry/Pastemask Top")
		(15 "B.Paste" user "Package Geometry/Pastemask Bottom")
		(5 "F.SilkS" user "Ref Des/Silkscreen Top")
		(7 "B.SilkS" user "Ref Des/Silkscreen Bottom")
		(1 "F.Mask" user "Board Geometry/Soldermask Top")
		(3 "B.Mask" user "Board Geometry/Soldermask Bottom")
		(17 "Dwgs.User" user "User.Drawings")
		(19 "Cmts.User" user "User.Comments")
		(21 "Eco1.User" user "User.Eco1")
		(23 "Eco2.User" user "User.Eco2")
		(25 "Edge.Cuts" user "Board Geometry/Outline")
		(27 "Margin" user)
		(31 "F.CrtYd" user "Package Geometry/Place Bound Top")
		(29 "B.CrtYd" user "Package Geometry/Place Bound Bottom")
		(35 "F.Fab" user "Ref Des/Assembly Top")
		(33 "B.Fab" user "Ref Des/Assembly Bottom")
	)
	(footprint ""
		(layer "F.Cu")
		(at 24.4094 -135.1788)
		(property "Reference" "PR94"
			(at 0 0 0)
			(layer "F.SilkS")
			(hide yes)
			(effects
				(font
					(size 1.27 1.27)
				)
			)
		)
		(property "Value" "0R2J-2-GP"
			(at 0.064008 -3.993896 0)
			(unlocked yes)
			(layer "F.Fab")
			(hide yes)
			(effects
				(font
					(size 1.016 1.016)
					(thickness 0.1524)
				)
			)
		)
		(property "Device Type" "R402H16"
			(at 0.064008 -5.517896 0)
			(unlocked yes)
			(layer "F.Fab")
			(hide yes)
			(effects
				(font
					(size 1.016 1.016)
					(thickness 0.1524)
				)
			)
		)
		(duplicate_pad_numbers_are_jumpers no)
		(fp_line
			(start -0.508 -0.9398)
			(end -0.508 0.9398)
			(stroke
				(width 0.1524)
				(type default)
			)
			(layer "F.SilkS")
		)
		(fp_line
			(start 0.508 -0.9398)
			(end -0.508 -0.9398)
			(stroke
				(width 0.1524)
				(type default)
			)
			(layer "F.SilkS")
		)
		(fp_rect
			(start -0.508 0.9398)
			(end 0.508 -0.9398)
			(stroke
				(width 0)
				(type default)
			)
			(fill no)
			(layer "F.CrtYd")
		)
		(fp_rect
			(start -0.508 0.9398)
			(end 0.508 -0.9398)
			(stroke
				(width 0)
				(type default)
			)
			(fill no)
			(layer "F.Fab")
		)
		(pad "1" smd custom
			(at 0 -0.4445)
			(size 0.1397 0.1397)
			(layers "F.Cu" "F.Mask" "F.Paste")
			(net "P12VU_2490_VCC")
			(options
				(clearance outline)
				(anchor circle)
			)
			(primitives
				(gr_poly
					(pts
						(arc
							(start -0.1778 -0.2794)
							(mid -0.249642 -0.249642)
							(end -0.2794 -0.1778)
						)
						(arc
							(start -0.2794 0.1778)
							(mid -0.249642 0.249642)
							(end -0.1778 0.2794)
						)
						(arc
							(start 0.1778 0.2794)
							(mid 0.249642 0.249642)
							(end 0.2794 0.1778)
						)
						(arc
							(start 0.2794 -0.1778)
							(mid 0.249642 -0.249642)
							(end 0.1778 -0.2794)
						)
					)
					(width 0)
					(fill yes)
				)
			)
		)
		(pad "2" smd custom
			(at 0 0.4445)
			(size 0.1397 0.1397)
			(layers "F.Cu" "F.Mask" "F.Paste")
			(net "P12V")
			(options
				(clearance outline)
				(anchor circle)
			)
			(primitives
				(gr_poly
					(pts
						(arc
							(start -0.1778 -0.2794)
							(mid -0.249642 -0.249642)
							(end -0.2794 -0.1778)
						)
						(arc
							(start -0.2794 0.1778)
							(mid -0.249642 0.249642)
							(end -0.1778 0.2794)
						)
						(arc
							(start 0.1778 0.2794)
							(mid 0.249642 0.249642)
							(end 0.2794 0.1778)
						)
						(arc
							(start 0.2794 -0.1778)
							(mid 0.249642 -0.249642)
							(end 0.1778 -0.2794)
						)
					)
					(width 0)
					(fill yes)
				)
			)
		)
	)
	(footprint ""
		(layer "F.Cu")
		(at 36.83 -240.665 180)
		(property "Reference" "R148"
			(at 0 0 180)
			(layer "F.SilkS")
			(hide yes)
			(effects
				(font
					(size 1.27 1.27)
				)
			)
		)
		(property "Value" "330R2J-3-GP"
			(at 0.064008 -3.993896 180)
			(unlocked yes)
			(layer "F.Fab")
			(hide yes)
			(effects
				(font
					(size 1.016 1.016)
					(thickness 0.1524)
				)
			)
		)
		(property "Device Type" "R402H16"
			(at 0.064008 -5.517896 180)
			(unlocked yes)
			(layer "F.Fab")
			(hide yes)
			(effects
				(font
					(size 1.016 1.016)
					(thickness 0.1524)
				)
			)
		)
		(duplicate_pad_numbers_are_jumpers no)
		(fp_line
			(start 0.508 -0.9398)
			(end -0.508 -0.9398)
			(stroke
				(width 0.1524)
				(type default)
			)
			(layer "F.SilkS")
		)
		(fp_line
			(start -0.508 -0.9398)
			(end -0.508 0.9398)
			(stroke
				(width 0.1524)
				(type default)
			)
			(layer "F.SilkS")
		)
		(fp_rect
			(start -0.508 0.9398)
			(end 0.508 -0.9398)
			(stroke
				(width 0)
				(type default)
			)
			(fill no)
			(layer "F.CrtYd")
		)
		(fp_rect
			(start -0.508 0.9398)
			(end 0.508 -0.9398)
			(stroke
				(width 0)
				(type default)
			)
			(fill no)
			(layer "F.Fab")
		)
		(pad "1" smd custom
			(at 0 -0.4445 180)
			(size 0.1397 0.1397)
			(layers "F.Cu" "F.Mask" "F.Paste")
			(net "P3V3")
			(options
				(clearance outline)
				(anchor circle)
			)
			(primitives
				(gr_poly
					(pts
						(arc
							(start -0.1778 -0.2794)
							(mid -0.249642 -0.249642)
							(end -0.2794 -0.1778)
						)
						(arc
							(start -0.2794 0.1778)
							(mid -0.249642 0.249642)
							(end -0.1778 0.2794)
						)
						(arc
							(start 0.1778 0.2794)
							(mid 0.249642 0.249642)
							(end 0.2794 0.1778)
						)
						(arc
							(start 0.2794 -0.1778)
							(mid 0.249642 -0.249642)
							(end 0.1778 -0.2794)
						)
					)
					(width 0)
					(fill yes)
				)
			)
		)
		(pad "2" smd custom
			(at 0 0.4445 180)
			(size 0.1397 0.1397)
			(layers "F.Cu" "F.Mask" "F.Paste")
			(net "LED_DR_LED0")
			(options
				(clearance outline)
				(anchor circle)
			)
			(primitives
				(gr_poly
					(pts
						(arc
							(start -0.1778 -0.2794)
							(mid -0.249642 -0.249642)
							(end -0.2794 -0.1778)
						)
						(arc
							(start -0.2794 0.1778)
							(mid -0.249642 0.249642)
							(end -0.1778 0.2794)
						)
						(arc
							(start 0.1778 0.2794)
							(mid 0.249642 0.249642)
							(end 0.2794 0.1778)
						)
						(arc
							(start 0.2794 -0.1778)
							(mid 0.249642 -0.249642)
							(end 0.1778 -0.2794)
						)
					)
					(width 0)
					(fill yes)
				)
			)
		)
	)
	(footprint ""
		(layer "F.Cu")
		(at 41.529 -252.984)
		(property "Reference" "R149"
			(at 0 0 0)
			(layer "F.SilkS")
			(hide yes)
			(effects
				(font
					(size 1.27 1.27)
				)
			)
		)
		(property "Value" "330R2J-3-GP"
			(at 0.064008 -3.993896 0)
			(unlocked yes)
			(layer "F.Fab")
			(hide yes)
			(effects
				(font
					(size 1.016 1.016)
					(thickness 0.1524)
				)
			)
		)
		(property "Device Type" "R402H16"
			(at 0.064008 -5.517896 0)
			(unlocked yes)
			(layer "F.Fab")
			(hide yes)
			(effects
				(font
					(size 1.016 1.016)
					(thickness 0.1524)
				)
			)
		)
		(duplicate_pad_numbers_are_jumpers no)
		(fp_line
			(start -0.508 -0.9398)
			(end -0.508 0.9398)
			(stroke
				(width 0.1524)
				(type default)
			)
			(layer "F.SilkS")
		)
		(fp_line
			(start 0.508 -0.9398)
			(end -0.508 -0.9398)
			(stroke
				(width 0.1524)
				(type default)
			)
			(layer "F.SilkS")
		)
		(fp_rect
			(start -0.508 0.9398)
			(end 0.508 -0.9398)
			(stroke
				(width 0)
				(type default)
			)
			(fill no)
			(layer "F.CrtYd")
		)
		(fp_rect
			(start -0.508 0.9398)
			(end 0.508 -0.9398)
			(stroke
				(width 0)
				(type default)
			)
			(fill no)
			(layer "F.Fab")
		)
		(pad "1" smd custom
			(at 0 -0.4445)
			(size 0.1397 0.1397)
			(layers "F.Cu" "F.Mask" "F.Paste")
			(net "P3V3")
			(options
				(clearance outline)
				(anchor circle)
			)
			(primitives
				(gr_poly
					(pts
						(arc
							(start -0.1778 -0.2794)
							(mid -0.249642 -0.249642)
							(end -0.2794 -0.1778)
						)
						(arc
							(start -0.2794 0.1778)
							(mid -0.249642 0.249642)
							(end -0.1778 0.2794)
						)
						(arc
							(start 0.1778 0.2794)
							(mid 0.249642 0.249642)
							(end 0.2794 0.1778)
						)
						(arc
							(start 0.2794 -0.1778)
							(mid 0.249642 -0.249642)
							(end 0.1778 -0.2794)
						)
					)
					(width 0)
					(fill yes)
				)
			)
		)
		(pad "2" smd custom
			(at 0 0.4445)
			(size 0.1397 0.1397)
			(layers "F.Cu" "F.Mask" "F.Paste")
			(net "LED_DR_LED4")
			(options
				(clearance outline)
				(anchor circle)
			)
			(primitives
				(gr_poly
					(pts
						(arc
							(start -0.1778 -0.2794)
							(mid -0.249642 -0.249642)
							(end -0.2794 -0.1778)
						)
						(arc
							(start -0.2794 0.1778)
							(mid -0.249642 0.249642)
							(end -0.1778 0.2794)
						)
						(arc
							(start 0.1778 0.2794)
							(mid 0.249642 0.249642)
							(end 0.2794 0.1778)
						)
						(arc
							(start 0.2794 -0.1778)
							(mid 0.249642 -0.249642)
							(end 0.1778 -0.2794)
						)
					)
					(width 0)
					(fill yes)
				)
			)
		)
	)
	(footprint ""
		(layer "F.Cu")
		(at 7.239 -454.1012 -90)
		(property "Reference" "C45"
			(at 0 0 270)
			(layer "F.SilkS")
			(hide yes)
			(effects
				(font
					(size 1.27 1.27)
				)
			)
		)
		(property "Value" "SCD1U16V2KX-3GP"
			(at 1.1811 -2.7051 270)
			(unlocked yes)
			(layer "F.Fab")
			(hide yes)
			(effects
				(font
					(size 1.016 1.016)
					(thickness 0.1524)
				)
			)
		)
		(property "Device Type" "C402H22"
			(at 1.1811 -4.2291 270)
			(unlocked yes)
			(layer "F.Fab")
			(hide yes)
			(effects
				(font
					(size 1.016 1.016)
					(thickness 0.1524)
				)
			)
		)
		(duplicate_pad_numbers_are_jumpers no)
		(fp_rect
			(start -0.4318 0.9525)
			(end 0.4318 -0.9525)
			(stroke
				(width 0)
				(type default)
			)
			(fill no)
			(layer "F.CrtYd")
		)
		(fp_rect
			(start -0.4318 0.9525)
			(end 0.4318 -0.9525)
			(stroke
				(width 0)
				(type default)
			)
			(fill no)
			(layer "F.Fab")
		)
		(pad "1" smd custom
			(at 0 -0.4445 270)
			(size 0.1524 0.1524)
			(layers "F.Cu" "F.Mask" "F.Paste")
			(net "FAN_TACH1")
			(options
				(clearance outline)
				(anchor circle)
			)
			(primitives
				(gr_poly
					(pts
						(arc
							(start 0.3048 -0.2032)
							(mid 0.275042 -0.275042)
							(end 0.2032 -0.3048)
						)
						(arc
							(start -0.2032 -0.3048)
							(mid -0.275042 -0.275042)
							(end -0.3048 -0.2032)
						)
						(arc
							(start -0.3048 0.2032)
							(mid -0.275042 0.275042)
							(end -0.2032 0.3048)
						)
						(arc
							(start 0.2032 0.3048)
							(mid 0.275042 0.275042)
							(end 0.3048 0.2032)
						)
					)
					(width 0)
					(fill yes)
				)
			)
		)
		(pad "2" smd custom
			(at 0 0.4445 270)
			(size 0.1524 0.1524)
			(layers "F.Cu" "F.Mask" "F.Paste")
			(net "GND")
			(options
				(clearance outline)
				(anchor circle)
			)
			(primitives
				(gr_poly
					(pts
						(arc
							(start 0.3048 -0.2032)
							(mid 0.275042 -0.275042)
							(end 0.2032 -0.3048)
						)
						(arc
							(start -0.2032 -0.3048)
							(mid -0.275042 -0.275042)
							(end -0.3048 -0.2032)
						)
						(arc
							(start -0.3048 0.2032)
							(mid -0.275042 0.275042)
							(end -0.2032 0.3048)
						)
						(arc
							(start 0.2032 0.3048)
							(mid 0.275042 0.275042)
							(end 0.3048 0.2032)
						)
					)
					(width 0)
					(fill yes)
				)
			)
		)
	)
	(footprint ""
		(layer "F.Cu")
		(at 26.67 -361.188)
		(property "Reference" "PR116"
			(at 0 0 0)
			(layer "F.SilkS")
			(hide yes)
			(effects
				(font
					(size 1.27 1.27)
				)
			)
		)
		(property "Value" "0R2J-2-GP"
			(at 0.064008 -3.993896 0)
			(unlocked yes)
			(layer "F.Fab")
			(hide yes)
			(effects
				(font
					(size 1.016 1.016)
					(thickness 0.1524)
				)
			)
		)
		(property "Device Type" "R402H16"
			(at 0.064008 -5.517896 0)
			(unlocked yes)
			(layer "F.Fab")
			(hide yes)
			(effects
				(font
					(size 1.016 1.016)
					(thickness 0.1524)
				)
			)
		)
		(duplicate_pad_numbers_are_jumpers no)
		(fp_line
			(start -0.508 -0.9398)
			(end -0.508 0.9398)
			(stroke
				(width 0.1524)
				(type default)
			)
			(layer "F.SilkS")
		)
		(fp_line
			(start 0.508 -0.9398)
			(end -0.508 -0.9398)
			(stroke
				(width 0.1524)
				(type default)
			)
			(layer "F.SilkS")
		)
		(fp_rect
			(start -0.508 0.9398)
			(end 0.508 -0.9398)
			(stroke
				(width 0)
				(type default)
			)
			(fill no)
			(layer "F.CrtYd")
		)
		(fp_rect
			(start -0.508 0.9398)
			(end 0.508 -0.9398)
			(stroke
				(width 0)
				(type default)
			)
			(fill no)
			(layer "F.Fab")
		)
		(pad "1" smd custom
			(at 0 -0.4445)
			(size 0.1397 0.1397)
			(layers "F.Cu" "F.Mask" "F.Paste")
			(net "ADM1276_LATCH#")
			(options
				(clearance outline)
				(anchor circle)
			)
			(primitives
				(gr_poly
					(pts
						(arc
							(start -0.1778 -0.2794)
							(mid -0.249642 -0.249642)
							(end -0.2794 -0.1778)
						)
						(arc
							(start -0.2794 0.1778)
							(mid -0.249642 0.249642)
							(end -0.1778 0.2794)
						)
						(arc
							(start 0.1778 0.2794)
							(mid 0.249642 0.249642)
							(end 0.2794 0.1778)
						)
						(arc
							(start 0.2794 -0.1778)
							(mid 0.249642 -0.249642)
							(end 0.1778 -0.2794)
						)
					)
					(width 0)
					(fill yes)
				)
			)
		)
		(pad "2" smd custom
			(at 0 0.4445)
			(size 0.1397 0.1397)
			(layers "F.Cu" "F.Mask" "F.Paste")
			(net "P3V3")
			(options
				(clearance outline)
				(anchor circle)
			)
			(primitives
				(gr_poly
					(pts
						(arc
							(start -0.1778 -0.2794)
							(mid -0.249642 -0.249642)
							(end -0.2794 -0.1778)
						)
						(arc
							(start -0.2794 0.1778)
							(mid -0.249642 0.249642)
							(end -0.1778 0.2794)
						)
						(arc
							(start 0.1778 0.2794)
							(mid 0.249642 0.249642)
							(end 0.2794 0.1778)
						)
						(arc
							(start 0.2794 -0.1778)
							(mid 0.249642 -0.249642)
							(end 0.1778 -0.2794)
						)
					)
					(width 0)
					(fill yes)
				)
			)
		)
	)
	(footprint ""
		(layer "F.Cu")
		(at 26.0604 -224.3074)
		(property "Reference" "R141"
			(at 0 0 0)
			(layer "F.SilkS")
			(hide yes)
			(effects
				(font
					(size 1.27 1.27)
				)
			)
		)
		(property "Value" "0R2J-2-GP"
			(at 0.064008 -3.993896 0)
			(unlocked yes)
			(layer "F.Fab")
			(hide yes)
			(effects
				(font
					(size 1.016 1.016)
					(thickness 0.1524)
				)
			)
		)
		(property "Device Type" "R402H16"
			(at 0.064008 -5.517896 0)
			(unlocked yes)
			(layer "F.Fab")
			(hide yes)
			(effects
				(font
					(size 1.016 1.016)
					(thickness 0.1524)
				)
			)
		)
		(duplicate_pad_numbers_are_jumpers no)
		(fp_line
			(start -0.508 -0.9398)
			(end -0.508 0.9398)
			(stroke
				(width 0.1524)
				(type default)
			)
			(layer "F.SilkS")
		)
		(fp_line
			(start 0.508 -0.9398)
			(end -0.508 -0.9398)
			(stroke
				(width 0.1524)
				(type default)
			)
			(layer "F.SilkS")
		)
		(fp_rect
			(start -0.508 0.9398)
			(end 0.508 -0.9398)
			(stroke
				(width 0)
				(type default)
			)
			(fill no)
			(layer "F.CrtYd")
		)
		(fp_rect
			(start -0.508 0.9398)
			(end 0.508 -0.9398)
			(stroke
				(width 0)
				(type default)
			)
			(fill no)
			(layer "F.Fab")
		)
		(pad "1" smd custom
			(at 0 -0.4445)
			(size 0.1397 0.1397)
			(layers "F.Cu" "F.Mask" "F.Paste")
			(net "PWM_OUT_FAN1_NET")
			(options
				(clearance outline)
				(anchor circle)
			)
			(primitives
				(gr_poly
					(pts
						(arc
							(start -0.1778 -0.2794)
							(mid -0.249642 -0.249642)
							(end -0.2794 -0.1778)
						)
						(arc
							(start -0.2794 0.1778)
							(mid -0.249642 0.249642)
							(end -0.1778 0.2794)
						)
						(arc
							(start 0.1778 0.2794)
							(mid 0.249642 0.249642)
							(end 0.2794 0.1778)
						)
						(arc
							(start 0.2794 -0.1778)
							(mid 0.249642 -0.249642)
							(end 0.1778 -0.2794)
						)
					)
					(width 0)
					(fill yes)
				)
			)
		)
		(pad "2" smd custom
			(at 0 0.4445)
			(size 0.1397 0.1397)
			(layers "F.Cu" "F.Mask" "F.Paste")
			(net "PWM_OUT_FAN1")
			(options
				(clearance outline)
				(anchor circle)
			)
			(primitives
				(gr_poly
					(pts
						(arc
							(start -0.1778 -0.2794)
							(mid -0.249642 -0.249642)
							(end -0.2794 -0.1778)
						)
						(arc
							(start -0.2794 0.1778)
							(mid -0.249642 0.249642)
							(end -0.1778 0.2794)
						)
						(arc
							(start 0.1778 0.2794)
							(mid 0.249642 0.249642)
							(end 0.2794 0.1778)
						)
						(arc
							(start 0.2794 -0.1778)
							(mid 0.249642 -0.249642)
							(end 0.1778 -0.2794)
						)
					)
					(width 0)
					(fill yes)
				)
			)
		)
	)
	(footprint ""
		(layer "F.Cu")
		(at 22.733 -179.8066 -90)
		(property "Reference" "R83"
			(at 0 0 270)
			(layer "F.SilkS")
			(hide yes)
			(effects
				(font
					(size 1.27 1.27)
				)
			)
		)
		(property "Value" "4K7R2F-GP"
			(at 0.064008 -3.993896 270)
			(unlocked yes)
			(layer "F.Fab")
			(hide yes)
			(effects
				(font
					(size 1.016 1.016)
					(thickness 0.1524)
				)
			)
		)
		(property "Device Type" "R402H16"
			(at 0.064008 -5.517896 270)
			(unlocked yes)
			(layer "F.Fab")
			(hide yes)
			(effects
				(font
					(size 1.016 1.016)
					(thickness 0.1524)
				)
			)
		)
		(duplicate_pad_numbers_are_jumpers no)
		(fp_line
			(start -0.508 -0.9398)
			(end -0.508 0.9398)
			(stroke
				(width 0.1524)
				(type default)
			)
			(layer "F.SilkS")
		)
		(fp_line
			(start 0.508 -0.9398)
			(end -0.508 -0.9398)
			(stroke
				(width 0.1524)
				(type default)
			)
			(layer "F.SilkS")
		)
		(fp_rect
			(start -0.508 0.9398)
			(end 0.508 -0.9398)
			(stroke
				(width 0)
				(type default)
			)
			(fill no)
			(layer "F.CrtYd")
		)
		(fp_rect
			(start -0.508 0.9398)
			(end 0.508 -0.9398)
			(stroke
				(width 0)
				(type default)
			)
			(fill no)
			(layer "F.Fab")
		)
		(pad "1" smd custom
			(at 0 -0.4445 270)
			(size 0.1397 0.1397)
			(layers "F.Cu" "F.Mask" "F.Paste")
			(net "P12V")
			(options
				(clearance outline)
				(anchor circle)
			)
			(primitives
				(gr_poly
					(pts
						(arc
							(start -0.1778 -0.2794)
							(mid -0.249642 -0.249642)
							(end -0.2794 -0.1778)
						)
						(arc
							(start -0.2794 0.1778)
							(mid -0.249642 0.249642)
							(end -0.1778 0.2794)
						)
						(arc
							(start 0.1778 0.2794)
							(mid 0.249642 0.249642)
							(end 0.2794 0.1778)
						)
						(arc
							(start 0.2794 -0.1778)
							(mid 0.249642 -0.249642)
							(end 0.1778 -0.2794)
						)
					)
					(width 0)
					(fill yes)
				)
			)
		)
		(pad "2" smd custom
			(at 0 0.4445 270)
			(size 0.1397 0.1397)
			(layers "F.Cu" "F.Mask" "F.Paste")
			(net "FAN_TACH7")
			(options
				(clearance outline)
				(anchor circle)
			)
			(primitives
				(gr_poly
					(pts
						(arc
							(start -0.1778 -0.2794)
							(mid -0.249642 -0.249642)
							(end -0.2794 -0.1778)
						)
						(arc
							(start -0.2794 0.1778)
							(mid -0.249642 0.249642)
							(end -0.1778 0.2794)
						)
						(arc
							(start 0.1778 0.2794)
							(mid 0.249642 0.249642)
							(end 0.2794 0.1778)
						)
						(arc
							(start 0.2794 -0.1778)
							(mid 0.249642 -0.249642)
							(end 0.1778 -0.2794)
						)
					)
					(width 0)
					(fill yes)
				)
			)
		)
	)
)
